(kicad_pcb
	(version 20260206)
	(generator "pcbnew")
	(generator_version "10.0")
	(general
		(thickness 1.6)
		(legacy_teardrops no)
	)
	(paper "A4")
	(title_block
		(title "netronome-mezz — pcbd0082-001_rev01_jul9_a.brd")
		(comment 1 "Open CloudServer (Microsoft) / footprints 410-420 of 714")
	)
	(layers
		(0 "F.Cu" signal "TOP")
		(4 "In1.Cu" signal "02_GND")
		(6 "In2.Cu" signal "03_SIG")
		(8 "In3.Cu" signal "04_SIG")
		(10 "In4.Cu" signal "05_GND")
		(12 "In5.Cu" signal "06_PWR1")
		(14 "In6.Cu" signal "07_SIG")
		(16 "In7.Cu" signal "08_SIG")
		(18 "In8.Cu" signal "09_GND")
		(2 "B.Cu" signal "BOTTOM")
		(9 "F.Adhes" user "F.Adhesive")
		(11 "B.Adhes" user "B.Adhesive")
		(13 "F.Paste" user "Package Geometry/Pastemask Top")
		(15 "B.Paste" user "Package Geometry/Pastemask Bottom")
		(5 "F.SilkS" user "Ref Des/Silkscreen Top")
		(7 "B.SilkS" user "Ref Des/Silkscreen Bottom")
		(1 "F.Mask" user "Board Geometry/Soldermask Top")
		(3 "B.Mask" user "Board Geometry/Soldermask Bottom")
		(17 "Dwgs.User" user "User.Drawings")
		(19 "Cmts.User" user "User.Comments")
		(21 "Eco1.User" user "User.Eco1")
		(23 "Eco2.User" user "User.Eco2")
		(25 "Edge.Cuts" user "Board Geometry/Outline")
		(27 "Margin" user)
		(31 "F.CrtYd" user "Package Geometry/Place Bound Top")
		(29 "B.CrtYd" user "Package Geometry/Place Bound Bottom")
		(35 "F.Fab" user "Ref Des/Assembly Top")
		(33 "B.Fab" user "Ref Des/Assembly Bottom")
		(45 "User.4" user "COMPVAL_TYPE_BOTTOM")
	)
	(footprint ""
		(layer "B.Cu")
		(at 49.237011 9.542018)
		(property "Reference" "C171"
			(at 0 0 0)
			(layer "B.SilkS")
			(hide yes)
			(effects
				(font
					(size 1.27 1.27)
				)
				(justify mirror)
			)
		)
		(property "Value" ""
			(at 0 0 0)
			(layer "B.Fab")
			(effects
				(font
					(size 1.27 1.27)
				)
				(justify mirror)
			)
		)
		(duplicate_pad_numbers_are_jumpers no)
		(fp_circle
			(center 0 0)
			(end 0.104648 0)
			(stroke
				(width 0.1016)
				(type default)
			)
			(fill no)
			(layer "B.SilkS")
		)
		(fp_poly
			(pts
				(xy 0.381 -0.889) (xy 0.381 0.889) (xy -0.381 0.889) (xy -0.381 -0.889)
			)
			(stroke
				(width 0)
				(type default)
			)
			(fill no)
			(layer "B.CrtYd")
		)
		(fp_line
			(start -0.508 -1.016)
			(end -0.508 1.016)
			(stroke
				(width 0.0254)
				(type default)
			)
			(layer "B.Fab")
		)
		(fp_line
			(start -0.508 1.016)
			(end 0.508 1.016)
			(stroke
				(width 0.0254)
				(type default)
			)
			(layer "B.Fab")
		)
		(fp_line
			(start 0.254 -1.016)
			(end -0.508 -1.016)
			(stroke
				(width 0.0254)
				(type default)
			)
			(layer "B.Fab")
		)
		(fp_line
			(start 0.508 -1.016)
			(end 0.254 -1.016)
			(stroke
				(width 0.0254)
				(type default)
			)
			(layer "B.Fab")
		)
		(fp_line
			(start 0.508 1.016)
			(end 0.508 -1.016)
			(stroke
				(width 0.0254)
				(type default)
			)
			(layer "B.Fab")
		)
		(pad "1" smd custom
			(at 0 -0.500126 180)
			(size 0.127 0.127)
			(layers "B.Cu" "B.Mask" "B.Paste")
			(net "VDDA_SERDES")
			(options
				(clearance outline)
				(anchor circle)
			)
			(primitives
				(gr_poly
					(pts
						(xy -0.1778 0.254) (xy 0.1778 0.254) (xy 0.254 0.1778) (xy 0.254 -0.1778) (xy 0.1778 -0.254) (xy -0.1778 -0.254)
						(xy -0.254 -0.1778) (xy -0.254 0.1778)
					)
					(width 0)
					(fill yes)
				)
			)
		)
		(pad "2" smd custom
			(at 0 0.500126 180)
			(size 0.127 0.127)
			(layers "B.Cu" "B.Mask" "B.Paste")
			(net "GND")
			(options
				(clearance outline)
				(anchor circle)
			)
			(primitives
				(gr_poly
					(pts
						(xy -0.1778 0.254) (xy 0.1778 0.254) (xy 0.254 0.1778) (xy 0.254 -0.1778) (xy 0.1778 -0.254) (xy -0.1778 -0.254)
						(xy -0.254 -0.1778) (xy -0.254 0.1778)
					)
					(width 0)
					(fill yes)
				)
			)
		)
	)
	(footprint ""
		(layer "B.Cu")
		(at 84.250987 29.812996)
		(property "Reference" "V3_A-A14"
			(at 0 0 0)
			(layer "B.SilkS")
			(hide yes)
			(effects
				(font
					(size 1.27 1.27)
				)
				(justify mirror)
			)
		)
		(property "Value" ""
			(at 0 0 0)
			(layer "B.Fab")
			(effects
				(font
					(size 1.27 1.27)
				)
				(justify mirror)
			)
		)
		(duplicate_pad_numbers_are_jumpers no)
		(pad "1" thru_hole circle
			(at 0 0 180)
			(size 0.4572 0.4572)
			(drill 0.20574)
			(layers "*.Cu" "*.Mask")
			(remove_unused_layers no)
			(net "DDR0_32A_A14")
			(clearance 0.1143)
			(thermal_gap 0.1143)
		)
	)
	(footprint ""
		(layer "B.Cu")
		(at 37.4015 26.416)
		(property "Reference" "L13"
			(at 1.2065 -0.73533 0)
			(unlocked yes)
			(layer "B.SilkS")
			(effects
				(font
					(size 0.7874 0.5842)
					(thickness 0.127)
				)
				(justify left mirror)
			)
		)
		(property "Value" ""
			(at 0 0 0)
			(layer "B.Fab")
			(effects
				(font
					(size 1.27 1.27)
				)
				(justify mirror)
			)
		)
		(duplicate_pad_numbers_are_jumpers no)
		(fp_line
			(start -0.0254 -0.127)
			(end -0.0254 0.127)
			(stroke
				(width 0.1016)
				(type default)
			)
			(layer "B.SilkS")
		)
		(fp_line
			(start -0.0254 0.127)
			(end 0.0254 0.127)
			(stroke
				(width 0.1016)
				(type default)
			)
			(layer "B.SilkS")
		)
		(fp_line
			(start 0.0254 -0.127)
			(end -0.0254 -0.127)
			(stroke
				(width 0.1016)
				(type default)
			)
			(layer "B.SilkS")
		)
		(fp_line
			(start 0.0254 0.127)
			(end 0.0254 -0.127)
			(stroke
				(width 0.1016)
				(type default)
			)
			(layer "B.SilkS")
		)
		(fp_poly
			(pts
				(xy -0.889 -0.4953) (xy -0.889 0.4953) (xy 0.889 0.4953) (xy 0.889 -0.4953)
			)
			(stroke
				(width 0)
				(type default)
			)
			(fill no)
			(layer "B.CrtYd")
		)
		(fp_line
			(start -0.508 -0.254)
			(end 0.508 -0.254)
			(stroke
				(width 0.0254)
				(type default)
			)
			(layer "B.Fab")
		)
		(fp_line
			(start -0.508 0.254)
			(end -0.508 -0.254)
			(stroke
				(width 0.0254)
				(type default)
			)
			(layer "B.Fab")
		)
		(fp_line
			(start 0.508 -0.254)
			(end 0.508 0.254)
			(stroke
				(width 0.0254)
				(type default)
			)
			(layer "B.Fab")
		)
		(fp_line
			(start 0.508 0.254)
			(end -0.508 0.254)
			(stroke
				(width 0.0254)
				(type default)
			)
			(layer "B.Fab")
		)
		(pad "1" smd rect
			(at 0.4699 0 180)
			(size 0.5334 0.508)
			(layers "B.Cu" "B.Mask" "B.Paste")
			(net "VDD_1.5V")
		)
		(pad "2" smd rect
			(at -0.4699 0 180)
			(size 0.5334 0.508)
			(layers "B.Cu" "B.Mask" "B.Paste")
			(net "VDDA_PLL")
		)
	)
	(footprint ""
		(layer "B.Cu")
		(at 83.450989 25.813004)
		(property "Reference" "V3_A-A09"
			(at 0 0 0)
			(layer "B.SilkS")
			(hide yes)
			(effects
				(font
					(size 1.27 1.27)
				)
				(justify mirror)
			)
		)
		(property "Value" ""
			(at 0 0 0)
			(layer "B.Fab")
			(effects
				(font
					(size 1.27 1.27)
				)
				(justify mirror)
			)
		)
		(duplicate_pad_numbers_are_jumpers no)
		(pad "1" thru_hole circle
			(at 0 0 180)
			(size 0.4572 0.4572)
			(drill 0.20574)
			(layers "*.Cu" "*.Mask")
			(remove_unused_layers no)
			(net "DDR0_32A_A9")
			(clearance 0.1143)
			(thermal_gap 0.1143)
		)
	)
	(footprint ""
		(layer "B.Cu")
		(at 82.65099 25.013006)
		(property "Reference" "V3_A-A05"
			(at 0 0 0)
			(layer "B.SilkS")
			(hide yes)
			(effects
				(font
					(size 1.27 1.27)
				)
				(justify mirror)
			)
		)
		(property "Value" ""
			(at 0 0 0)
			(layer "B.Fab")
			(effects
				(font
					(size 1.27 1.27)
				)
				(justify mirror)
			)
		)
		(duplicate_pad_numbers_are_jumpers no)
		(pad "1" thru_hole circle
			(at 0 0 180)
			(size 0.4572 0.4572)
			(drill 0.20574)
			(layers "*.Cu" "*.Mask")
			(remove_unused_layers no)
			(net "DDR0_32A_A5")
			(clearance 0.1143)
			(thermal_gap 0.1143)
		)
	)
	(footprint ""
		(layer "B.Cu")
		(at 49.403 0.762 180)
		(property "Reference" "C151"
			(at 0.145212 0.8763 270)
			(unlocked yes)
			(layer "B.SilkS")
			(effects
				(font
					(size 0.7874 0.5842)
					(thickness 0.127)
				)
				(justify left mirror)
			)
		)
		(property "Value" "0.22UF"
			(at 0.091846 0.2921 90)
			(unlocked yes)
			(layer "B.Fab")
			(hide yes)
			(effects
				(font
					(size 0.7874 0.5842)
					(thickness 0.2032)
				)
				(justify left mirror)
			)
		)
		(property "Device Type" "CAPC0062"
			(at 0.091846 0.2921 90)
			(unlocked yes)
			(layer "B.Fab")
			(hide yes)
			(effects
				(font
					(size 0.7874 0.5842)
					(thickness 0.2032)
				)
				(justify left mirror)
			)
		)
		(duplicate_pad_numbers_are_jumpers no)
		(fp_poly
			(pts
				(xy -0.635 1.0668) (xy -0.635 -1.0668) (xy 0.635 -1.0668) (xy 0.635 1.0668)
			)
			(stroke
				(width 0)
				(type default)
			)
			(fill no)
			(layer "B.CrtYd")
		)
		(fp_line
			(start 0.254 0.508)
			(end 0.254 -0.508)
			(stroke
				(width 0.0254)
				(type default)
			)
			(layer "B.Fab")
		)
		(fp_line
			(start 0.254 -0.508)
			(end -0.254 -0.508)
			(stroke
				(width 0.0254)
				(type default)
			)
			(layer "B.Fab")
		)
		(fp_line
			(start -0.254 0.508)
			(end 0.254 0.508)
			(stroke
				(width 0.0254)
				(type default)
			)
			(layer "B.Fab")
		)
		(fp_line
			(start -0.254 -0.508)
			(end -0.254 0.508)
			(stroke
				(width 0.0254)
				(type default)
			)
			(layer "B.Fab")
		)
		(pad "1" smd rect
			(at 0 -0.4191)
			(size 0.508 0.5334)
			(layers "B.Cu" "B.Mask" "B.Paste")
			(net "_NFP_PCIE0_PER7_P")
		)
		(pad "2" smd rect
			(at 0 0.4191)
			(size 0.508 0.5334)
			(layers "B.Cu" "B.Mask" "B.Paste")
			(net "NFP_PCIE0_PER7_P")
		)
		(zone
			(layer "B.Cu")
			(hatch none 0.5)
			(connect_pads
				(clearance 0)
			)
			(min_thickness 0.25)
			(keepout
				(tracks not_allowed)
				(vias allowed)
				(pads allowed)
				(copperpour not_allowed)
				(footprints allowed)
			)
			(placement
				(enabled no)
				(sheetname "")
			)
			(fill
				(thermal_gap 0.5)
				(thermal_bridge_width 0.5)
				(island_removal_mode 0)
			)
			(polygon
				(pts
					(xy 49.4284 0.7874) (xy 49.4284 0.7366) (xy 49.3776 0.7366) (xy 49.3776 0.7874)
				)
			)
		)
	)
	(footprint ""
		(layer "B.Cu")
		(at 82.65099 14.256004)
		(property "Reference" "V2_A-A02"
			(at 0 0 0)
			(layer "B.SilkS")
			(hide yes)
			(effects
				(font
					(size 1.27 1.27)
				)
				(justify mirror)
			)
		)
		(property "Value" ""
			(at 0 0 0)
			(layer "B.Fab")
			(effects
				(font
					(size 1.27 1.27)
				)
				(justify mirror)
			)
		)
		(duplicate_pad_numbers_are_jumpers no)
		(pad "1" thru_hole circle
			(at 0 0 180)
			(size 0.4572 0.4572)
			(drill 0.20574)
			(layers "*.Cu" "*.Mask")
			(remove_unused_layers no)
			(net "DDR0_32A_A2")
			(clearance 0.1143)
			(thermal_gap 0.1143)
		)
	)
	(footprint ""
		(layer "B.Cu")
		(at 68.236973 17.542002 180)
		(property "Reference" "C76"
			(at -0.951357 -0.491998 270)
			(unlocked yes)
			(layer "B.SilkS")
			(effects
				(font
					(size 0.7874 0.5842)
					(thickness 0.127)
				)
				(justify mirror)
			)
		)
		(property "Value" ""
			(at 0 0 0)
			(layer "B.Fab")
			(effects
				(font
					(size 1.27 1.27)
				)
				(justify mirror)
			)
		)
		(duplicate_pad_numbers_are_jumpers no)
		(fp_circle
			(center 0 0)
			(end -0.104648 0)
			(stroke
				(width 0.1016)
				(type default)
			)
			(fill no)
			(layer "B.SilkS")
		)
		(fp_poly
			(pts
				(xy 0.381 -0.889) (xy 0.381 0.889) (xy -0.381 0.889) (xy -0.381 -0.889)
			)
			(stroke
				(width 0)
				(type default)
			)
			(fill no)
			(layer "B.CrtYd")
		)
		(fp_line
			(start 0.508 1.016)
			(end 0.508 -1.016)
			(stroke
				(width 0.0254)
				(type default)
			)
			(layer "B.Fab")
		)
		(fp_line
			(start 0.508 -1.016)
			(end 0.254 -1.016)
			(stroke
				(width 0.0254)
				(type default)
			)
			(layer "B.Fab")
		)
		(fp_line
			(start 0.254 -1.016)
			(end -0.508 -1.016)
			(stroke
				(width 0.0254)
				(type default)
			)
			(layer "B.Fab")
		)
		(fp_line
			(start -0.508 1.016)
			(end 0.508 1.016)
			(stroke
				(width 0.0254)
				(type default)
			)
			(layer "B.Fab")
		)
		(fp_line
			(start -0.508 -1.016)
			(end -0.508 1.016)
			(stroke
				(width 0.0254)
				(type default)
			)
			(layer "B.Fab")
		)
		(pad "1" smd custom
			(at 0 -0.500126)
			(size 0.127 0.127)
			(layers "B.Cu" "B.Mask" "B.Paste")
			(net "DDR_VDDQ")
			(options
				(clearance outline)
				(anchor circle)
			)
			(primitives
				(gr_poly
					(pts
						(xy -0.1778 0.254) (xy 0.1778 0.254) (xy 0.254 0.1778) (xy 0.254 -0.1778) (xy 0.1778 -0.254) (xy -0.1778 -0.254)
						(xy -0.254 -0.1778) (xy -0.254 0.1778)
					)
					(width 0)
					(fill yes)
				)
			)
		)
		(pad "2" smd custom
			(at 0 0.500126)
			(size 0.127 0.127)
			(layers "B.Cu" "B.Mask" "B.Paste")
			(net "GND")
			(options
				(clearance outline)
				(anchor circle)
			)
			(primitives
				(gr_poly
					(pts
						(xy -0.1778 0.254) (xy 0.1778 0.254) (xy 0.254 0.1778) (xy 0.254 -0.1778) (xy 0.1778 -0.254) (xy -0.1778 -0.254)
						(xy -0.254 -0.1778) (xy -0.254 0.1778)
					)
					(width 0)
					(fill yes)
				)
			)
		)
	)
	(footprint ""
		(layer "B.Cu")
		(at 37.592 21.971 -90)
		(property "Reference" "R204"
			(at 0 0 90)
			(layer "B.SilkS")
			(hide yes)
			(effects
				(font
					(size 1.27 1.27)
				)
				(justify mirror)
			)
		)
		(property "Value" "39.0"
			(at 0.148158 1.3462 180)
			(unlocked yes)
			(layer "B.Fab")
			(hide yes)
			(effects
				(font
					(size 1.27 0.9652)
					(thickness 0.000001)
				)
				(justify left mirror)
			)
		)
		(property "Device Type" "REST0108"
			(at 0.148158 1.3462 180)
			(unlocked yes)
			(layer "B.Fab")
			(hide yes)
			(effects
				(font
					(size 1.27 0.9652)
					(thickness 0.000001)
				)
				(justify left mirror)
			)
		)
		(duplicate_pad_numbers_are_jumpers no)
		(fp_poly
			(pts
				(xy -0.635 1.0668) (xy -0.635 -1.0668) (xy 0.635 -1.0668) (xy 0.635 1.0668)
			)
			(stroke
				(width 0)
				(type default)
			)
			(fill no)
			(layer "B.CrtYd")
		)
		(fp_line
			(start -0.254 0.508)
			(end 0.254 0.508)
			(stroke
				(width 0.0254)
				(type default)
			)
			(layer "B.Fab")
		)
		(fp_line
			(start 0.254 0.508)
			(end 0.254 -0.508)
			(stroke
				(width 0.0254)
				(type default)
			)
			(layer "B.Fab")
		)
		(fp_line
			(start -0.254 -0.508)
			(end -0.254 0.508)
			(stroke
				(width 0.0254)
				(type default)
			)
			(layer "B.Fab")
		)
		(fp_line
			(start 0.254 -0.508)
			(end -0.254 -0.508)
			(stroke
				(width 0.0254)
				(type default)
			)
			(layer "B.Fab")
		)
		(pad "1" smd rect
			(at 0 -0.4191 90)
			(size 0.508 0.5334)
			(layers "B.Cu" "B.Mask" "B.Paste")
			(net "_NFP_ARM_SPI_FLASH_SCK")
		)
		(pad "2" smd rect
			(at 0 0.4191 90)
			(size 0.508 0.5334)
			(layers "B.Cu" "B.Mask" "B.Paste")
			(net "NFP_ARM_SPI_FLASH_SCK")
		)
		(zone
			(layer "B.Cu")
			(hatch none 0.5)
			(connect_pads
				(clearance 0)
			)
			(min_thickness 0.25)
			(keepout
				(tracks not_allowed)
				(vias allowed)
				(pads allowed)
				(copperpour not_allowed)
				(footprints allowed)
			)
			(placement
				(enabled no)
				(sheetname "")
			)
			(fill
				(thermal_gap 0.5)
				(thermal_bridge_width 0.5)
				(island_removal_mode 0)
			)
			(polygon
				(pts
					(xy 37.6174 21.9456) (xy 37.5666 21.9456) (xy 37.5666 21.9964) (xy 37.6174 21.9964)
				)
			)
		)
	)
	(footprint ""
		(layer "B.Cu")
		(at 61.736986 15.042007 90)
		(property "Reference" "R283"
			(at 0 0 90)
			(layer "B.SilkS")
			(hide yes)
			(effects
				(font
					(size 1.27 1.27)
				)
				(justify mirror)
			)
		)
		(property "Value" ""
			(at 0 0 90)
			(layer "B.Fab")
			(effects
				(font
					(size 1.27 1.27)
				)
				(justify mirror)
			)
		)
		(duplicate_pad_numbers_are_jumpers no)
		(fp_circle
			(center 0 0)
			(end 0 0.104648)
			(stroke
				(width 0.1016)
				(type default)
			)
			(fill no)
			(layer "B.SilkS")
		)
		(fp_poly
			(pts
				(xy 0.381 -0.889) (xy 0.381 0.889) (xy -0.381 0.889) (xy -0.381 -0.889)
			)
			(stroke
				(width 0)
				(type default)
			)
			(fill no)
			(layer "B.CrtYd")
		)
		(fp_line
			(start 0.508 -1.016)
			(end 0.254 -1.016)
			(stroke
				(width 0.0254)
				(type default)
			)
			(layer "B.Fab")
		)
		(fp_line
			(start 0.254 -1.016)
			(end -0.508 -1.016)
			(stroke
				(width 0.0254)
				(type default)
			)
			(layer "B.Fab")
		)
		(fp_line
			(start -0.508 -1.016)
			(end -0.508 1.016)
			(stroke
				(width 0.0254)
				(type default)
			)
			(layer "B.Fab")
		)
		(fp_line
			(start 0.508 1.016)
			(end 0.508 -1.016)
			(stroke
				(width 0.0254)
				(type default)
			)
			(layer "B.Fab")
		)
		(fp_line
			(start -0.508 1.016)
			(end 0.508 1.016)
			(stroke
				(width 0.0254)
				(type default)
			)
			(layer "B.Fab")
		)
		(pad "1" smd custom
			(at 0 -0.500126 270)
			(size 0.127 0.127)
			(layers "B.Cu" "B.Mask" "B.Paste")
			(net "GND")
			(options
				(clearance outline)
				(anchor circle)
			)
			(primitives
				(gr_poly
					(pts
						(xy -0.1778 0.254) (xy 0.1778 0.254) (xy 0.254 0.1778) (xy 0.254 -0.1778) (xy 0.1778 -0.254) (xy -0.1778 -0.254)
						(xy -0.254 -0.1778) (xy -0.254 0.1778)
					)
					(width 0)
					(fill yes)
				)
			)
		)
		(pad "2" smd custom
			(at 0 0.500126 270)
			(size 0.127 0.127)
			(layers "B.Cu" "B.Mask" "B.Paste")
			(net "DDR0_32A_VREF")
			(options
				(clearance outline)
				(anchor circle)
			)
			(primitives
				(gr_poly
					(pts
						(xy -0.1778 0.254) (xy 0.1778 0.254) (xy 0.254 0.1778) (xy 0.254 -0.1778) (xy 0.1778 -0.254) (xy -0.1778 -0.254)
						(xy -0.254 -0.1778) (xy -0.254 0.1778)
					)
					(width 0)
					(fill yes)
				)
			)
		)
	)
	(footprint ""
		(layer "B.Cu")
		(at 68.236973 6.542024)
		(property "Reference" "R146"
			(at -1.207643 0.823976 270)
			(unlocked yes)
			(layer "B.SilkS")
			(effects
				(font
					(size 0.7874 0.5842)
					(thickness 0.127)
				)
				(justify mirror)
			)
		)
		(property "Value" ""
			(at 0 0 0)
			(layer "B.Fab")
			(effects
				(font
					(size 1.27 1.27)
				)
				(justify mirror)
			)
		)
		(duplicate_pad_numbers_are_jumpers no)
		(fp_circle
			(center 0 0)
			(end 0.104648 0)
			(stroke
				(width 0.1016)
				(type default)
			)
			(fill no)
			(layer "B.SilkS")
		)
		(fp_poly
			(pts
				(xy 0.381 -0.889) (xy 0.381 0.889) (xy -0.381 0.889) (xy -0.381 -0.889)
			)
			(stroke
				(width 0)
				(type default)
			)
			(fill no)
			(layer "B.CrtYd")
		)
		(fp_line
			(start -0.508 -1.016)
			(end -0.508 1.016)
			(stroke
				(width 0.0254)
				(type default)
			)
			(layer "B.Fab")
		)
		(fp_line
			(start -0.508 1.016)
			(end 0.508 1.016)
			(stroke
				(width 0.0254)
				(type default)
			)
			(layer "B.Fab")
		)
		(fp_line
			(start 0.254 -1.016)
			(end -0.508 -1.016)
			(stroke
				(width 0.0254)
				(type default)
			)
			(layer "B.Fab")
		)
		(fp_line
			(start 0.508 -1.016)
			(end 0.254 -1.016)
			(stroke
				(width 0.0254)
				(type default)
			)
			(layer "B.Fab")
		)
		(fp_line
			(start 0.508 1.016)
			(end 0.508 -1.016)
			(stroke
				(width 0.0254)
				(type default)
			)
			(layer "B.Fab")
		)
		(pad "1" smd custom
			(at 0 -0.500126 180)
			(size 0.127 0.127)
			(layers "B.Cu" "B.Mask" "B.Paste")
			(net "GND")
			(options
				(clearance outline)
				(anchor circle)
			)
			(primitives
				(gr_poly
					(pts
						(xy -0.1778 0.254) (xy 0.1778 0.254) (xy 0.254 0.1778) (xy 0.254 -0.1778) (xy 0.1778 -0.254) (xy -0.1778 -0.254)
						(xy -0.254 -0.1778) (xy -0.254 0.1778)
					)
					(width 0)
					(fill yes)
				)
			)
		)
		(pad "2" smd custom
			(at 0 0.500126 180)
			(size 0.127 0.127)
			(layers "B.Cu" "B.Mask" "B.Paste")
			(net "DDR_VDDQ")
			(options
				(clearance outline)
				(anchor circle)
			)
			(primitives
				(gr_poly
					(pts
						(xy -0.1778 0.254) (xy 0.1778 0.254) (xy 0.254 0.1778) (xy 0.254 -0.1778) (xy 0.1778 -0.254) (xy -0.1778 -0.254)
						(xy -0.254 -0.1778) (xy -0.254 0.1778)
					)
					(width 0)
					(fill yes)
				)
			)
		)
	)
)
